(kicad_pcb
	(version 20260206)
	(generator "pcbnew")
	(generator_version "10.0")
	(general
		(thickness 1.6)
		(legacy_teardrops no)
	)
	(paper "A4")
	(title_block
		(title "timecard-production-celestica-r4006 — R4006-B0001-02_R01.brd")
		(comment 1 "Time Appliance Project (Time Card) / footprints 580-587 of 1113")
	)
	(layers
		(0 "F.Cu" signal "TOP")
		(4 "In1.Cu" signal "L02_GND1")
		(6 "In2.Cu" signal "L03_SIG1")
		(8 "In3.Cu" signal "L04_GND2")
		(10 "In4.Cu" signal "L05_VCC1")
		(12 "In5.Cu" signal "L06_VCC2")
		(14 "In6.Cu" signal "L07_GND3")
		(16 "In7.Cu" signal "L08_SIG2")
		(18 "In8.Cu" signal "L09_GND4")
		(2 "B.Cu" signal "BOTTOM")
		(9 "F.Adhes" user "F.Adhesive")
		(11 "B.Adhes" user "B.Adhesive")
		(13 "F.Paste" user "Package Geometry/Pastemask Top")
		(15 "B.Paste" user "Package Geometry/Pastemask Bottom")
		(5 "F.SilkS" user "Ref Des/Silkscreen Top")
		(7 "B.SilkS" user "Ref Des/Silkscreen Bottom")
		(1 "F.Mask" user "Board Geometry/Soldermask Top")
		(3 "B.Mask" user "Board Geometry/Soldermask Bottom")
		(17 "Dwgs.User" user "User.Drawings")
		(19 "Cmts.User" user "User.Comments")
		(21 "Eco1.User" user "User.Eco1")
		(23 "Eco2.User" user "User.Eco2")
		(25 "Edge.Cuts" user "Board Geometry/Outline")
		(27 "Margin" user)
		(31 "F.CrtYd" user "Package Geometry/Place Bound Top")
		(29 "B.CrtYd" user "Package Geometry/Place Bound Bottom")
		(35 "F.Fab" user "Ref Des/Assembly Top")
		(33 "B.Fab" user "Ref Des/Assembly Bottom")
	)
	(footprint ""
		(layer "F.Cu")
		(at 154.153108 -49.01311 90)
		(property "Reference" "R67"
			(at 0.00889 2.604262 90)
			(unlocked yes)
			(layer "F.SilkS")
			(effects
				(font
					(size 0.7874 0.5842)
					(thickness 0.1524)
				)
			)
		)
		(property "Value" "VAL*"
			(at 0.02032 2.13233 90)
			(unlocked yes)
			(layer "F.Fab")
			(hide yes)
			(effects
				(font
					(size 0.7874 0.5842)
					(thickness 0.1524)
				)
			)
		)
		(property "Device Type" "RESISTOR-G155-133R0-01,33OHM,1%"
			(at 0.008382 1.210564 90)
			(unlocked yes)
			(layer "F.Fab")
			(hide yes)
			(effects
				(font
					(size 0.7874 0.5842)
					(thickness 0.1524)
				)
			)
		)
		(property "User Part Number" "PARTNUM*"
			(at 0.02032 4.024884 90)
			(unlocked yes)
			(layer "Cmts.User")
			(hide yes)
			(effects
				(font
					(size 0.7874 0.5842)
					(thickness 0.1524)
				)
			)
		)
		(property "Tolerance" "TOL*"
			(at 0.044704 3.05435 90)
			(unlocked yes)
			(layer "Cmts.User")
			(hide yes)
			(effects
				(font
					(size 0.7874 0.5842)
					(thickness 0.1524)
				)
			)
		)
		(duplicate_pad_numbers_are_jumpers no)
		(fp_line
			(start 1.143 -0.5588)
			(end -1.143 -0.5588)
			(stroke
				(width 0.1)
				(type default)
			)
			(layer "F.SilkS")
		)
		(fp_line
			(start -1.143 -0.5588)
			(end -1.143 0.5588)
			(stroke
				(width 0.1)
				(type default)
			)
			(layer "F.SilkS")
		)
		(fp_line
			(start 1.143 0.5588)
			(end 1.143 -0.5588)
			(stroke
				(width 0.1)
				(type default)
			)
			(layer "F.SilkS")
		)
		(fp_line
			(start -1.143 0.5588)
			(end 1.143 0.5588)
			(stroke
				(width 0.1)
				(type default)
			)
			(layer "F.SilkS")
		)
		(fp_rect
			(start 1.143 0.5588)
			(end -1.143 -0.5588)
			(stroke
				(width 0)
				(type default)
			)
			(fill no)
			(layer "F.CrtYd")
		)
		(fp_line
			(start 0.508 -0.3048)
			(end -0.508 -0.3048)
			(stroke
				(width 0.1)
				(type default)
			)
			(layer "F.Fab")
		)
		(fp_line
			(start -0.508 -0.3048)
			(end -0.508 0.3048)
			(stroke
				(width 0.1)
				(type default)
			)
			(layer "F.Fab")
		)
		(fp_line
			(start 0.508 0.3048)
			(end 0.508 -0.3048)
			(stroke
				(width 0.1)
				(type default)
			)
			(layer "F.Fab")
		)
		(fp_line
			(start -0.508 0.3048)
			(end 0.508 0.3048)
			(stroke
				(width 0.1)
				(type default)
			)
			(layer "F.Fab")
		)
		(pad "1" smd rect
			(at -0.5334 0 90)
			(size 0.7112 0.6096)
			(layers "F.Cu" "F.Mask" "F.Paste")
			(net "SHT3X_I2C_SCL")
		)
		(pad "2" smd rect
			(at 0.5334 0 90)
			(size 0.7112 0.6096)
			(layers "F.Cu" "F.Mask" "F.Paste")
			(net "R_SHT3X_I2C_SCL")
		)
		(zone
			(layer "F.Cu")
			(hatch none 0.5)
			(connect_pads
				(clearance 0)
			)
			(min_thickness 0.25)
			(keepout
				(tracks allowed)
				(vias not_allowed)
				(pads allowed)
				(copperpour not_allowed)
				(footprints allowed)
			)
			(placement
				(enabled no)
				(sheetname "")
			)
			(fill
				(thermal_gap 0.5)
				(thermal_bridge_width 0.5)
				(island_removal_mode 0)
			)
			(polygon
				(pts
					(xy 154.457908 -49.08931) (xy 153.848308 -49.08931) (xy 153.848308 -48.93691) (xy 154.457908 -48.93691)
				)
			)
		)
	)
	(footprint ""
		(layer "F.Cu")
		(at 72.136 -128.27)
		(property "Reference" "SP31"
			(at 0 0 0)
			(layer "F.SilkS")
			(hide yes)
			(effects
				(font
					(size 1.27 1.27)
				)
			)
		)
		(property "Value" ""
			(at 0 0 0)
			(layer "F.Fab")
			(effects
				(font
					(size 1.27 1.27)
				)
			)
		)
		(duplicate_pad_numbers_are_jumpers no)
	)
	(footprint ""
		(layer "F.Cu")
		(at 83.439 -64.3128 90)
		(property "Reference" "R303"
			(at 13.4112 -9.73963 90)
			(unlocked yes)
			(layer "F.SilkS")
			(effects
				(font
					(size 0.7874 0.5842)
					(thickness 0.1524)
				)
			)
		)
		(property "Value" "VAL*"
			(at 0.02032 2.13233 90)
			(unlocked yes)
			(layer "F.Fab")
			(hide yes)
			(effects
				(font
					(size 0.7874 0.5842)
					(thickness 0.1524)
				)
			)
		)
		(property "Device Type" "RESISTOR-G155-11001-01,1KOHM,1%"
			(at 0.008382 1.210564 90)
			(unlocked yes)
			(layer "F.Fab")
			(hide yes)
			(effects
				(font
					(size 0.7874 0.5842)
					(thickness 0.1524)
				)
			)
		)
		(property "User Part Number" "PARTNUM*"
			(at 0.02032 4.024884 90)
			(unlocked yes)
			(layer "Cmts.User")
			(hide yes)
			(effects
				(font
					(size 0.7874 0.5842)
					(thickness 0.1524)
				)
			)
		)
		(property "Tolerance" "TOL*"
			(at 0.044704 3.05435 90)
			(unlocked yes)
			(layer "Cmts.User")
			(hide yes)
			(effects
				(font
					(size 0.7874 0.5842)
					(thickness 0.1524)
				)
			)
		)
		(duplicate_pad_numbers_are_jumpers no)
		(fp_line
			(start 1.143 -0.5588)
			(end -1.143 -0.5588)
			(stroke
				(width 0.1)
				(type default)
			)
			(layer "F.SilkS")
		)
		(fp_line
			(start -1.143 -0.5588)
			(end -1.143 0.5588)
			(stroke
				(width 0.1)
				(type default)
			)
			(layer "F.SilkS")
		)
		(fp_line
			(start 1.143 0.5588)
			(end 1.143 -0.5588)
			(stroke
				(width 0.1)
				(type default)
			)
			(layer "F.SilkS")
		)
		(fp_line
			(start -1.143 0.5588)
			(end 1.143 0.5588)
			(stroke
				(width 0.1)
				(type default)
			)
			(layer "F.SilkS")
		)
		(fp_rect
			(start -1.143 -0.5588)
			(end 1.143 0.5588)
			(stroke
				(width 0)
				(type default)
			)
			(fill no)
			(layer "F.CrtYd")
		)
		(fp_line
			(start 0.508 -0.3048)
			(end -0.508 -0.3048)
			(stroke
				(width 0.1)
				(type default)
			)
			(layer "F.Fab")
		)
		(fp_line
			(start -0.508 -0.3048)
			(end -0.508 0.3048)
			(stroke
				(width 0.1)
				(type default)
			)
			(layer "F.Fab")
		)
		(fp_line
			(start 0.508 0.3048)
			(end 0.508 -0.3048)
			(stroke
				(width 0.1)
				(type default)
			)
			(layer "F.Fab")
		)
		(fp_line
			(start -0.508 0.3048)
			(end 0.508 0.3048)
			(stroke
				(width 0.1)
				(type default)
			)
			(layer "F.Fab")
		)
		(pad "1" smd rect
			(at -0.5334 0 90)
			(size 0.7112 0.6096)
			(layers "F.Cu" "F.Mask" "F.Paste")
			(net "UNNAMED_9_BNO080LGA28_I29_PS1")
		)
		(pad "2" smd rect
			(at 0.5334 0 90)
			(size 0.7112 0.6096)
			(layers "F.Cu" "F.Mask" "F.Paste")
			(net "SG")
		)
		(zone
			(layer "F.Cu")
			(hatch none 0.5)
			(connect_pads
				(clearance 0)
			)
			(min_thickness 0.25)
			(keepout
				(tracks allowed)
				(vias not_allowed)
				(pads allowed)
				(copperpour not_allowed)
				(footprints allowed)
			)
			(placement
				(enabled no)
				(sheetname "")
			)
			(fill
				(thermal_gap 0.5)
				(thermal_bridge_width 0.5)
				(island_removal_mode 0)
			)
			(polygon
				(pts
					(xy 83.1342 -64.2366) (xy 83.7438 -64.2366) (xy 83.7438 -64.389) (xy 83.1342 -64.389)
				)
			)
		)
	)
	(footprint ""
		(layer "F.Cu")
		(at 28.067 -94.234 -90)
		(property "Reference" "R129"
			(at -4.953 0.59563 90)
			(unlocked yes)
			(layer "F.SilkS")
			(effects
				(font
					(size 0.7874 0.5842)
					(thickness 0.1524)
				)
			)
		)
		(property "Value" "VAL*"
			(at 0.02032 2.13233 270)
			(unlocked yes)
			(layer "F.Fab")
			(hide yes)
			(effects
				(font
					(size 0.7874 0.5842)
					(thickness 0.1524)
				)
			)
		)
		(property "Tolerance" "TOL*"
			(at 0.044704 3.05435 270)
			(unlocked yes)
			(layer "Cmts.User")
			(hide yes)
			(effects
				(font
					(size 0.7874 0.5842)
					(thickness 0.1524)
				)
			)
		)
		(property "User Part Number" "PARTNUM*"
			(at 0.02032 4.024884 270)
			(unlocked yes)
			(layer "Cmts.User")
			(hide yes)
			(effects
				(font
					(size 0.7874 0.5842)
					(thickness 0.1524)
				)
			)
		)
		(property "Device Type" "RESISTOR-G155-100R0-J0,0OHM,-"
			(at 0.008382 1.210564 270)
			(unlocked yes)
			(layer "F.Fab")
			(hide yes)
			(effects
				(font
					(size 0.7874 0.5842)
					(thickness 0.1524)
				)
			)
		)
		(duplicate_pad_numbers_are_jumpers no)
		(fp_line
			(start -1.143 0.5588)
			(end 1.143 0.5588)
			(stroke
				(width 0.1)
				(type default)
			)
			(layer "F.SilkS")
		)
		(fp_line
			(start 1.143 0.5588)
			(end 1.143 -0.5588)
			(stroke
				(width 0.1)
				(type default)
			)
			(layer "F.SilkS")
		)
		(fp_line
			(start -1.143 -0.5588)
			(end -1.143 0.5588)
			(stroke
				(width 0.1)
				(type default)
			)
			(layer "F.SilkS")
		)
		(fp_line
			(start 1.143 -0.5588)
			(end -1.143 -0.5588)
			(stroke
				(width 0.1)
				(type default)
			)
			(layer "F.SilkS")
		)
		(fp_poly
			(pts
				(xy -1.143 0.5588) (xy 1.143 0.5588) (xy 1.143 -0.5588) (xy -1.143 -0.5588)
			)
			(stroke
				(width 0)
				(type default)
			)
			(fill no)
			(layer "F.CrtYd")
		)
		(fp_line
			(start -0.508 0.3048)
			(end 0.508 0.3048)
			(stroke
				(width 0.1)
				(type default)
			)
			(layer "F.Fab")
		)
		(fp_line
			(start 0.508 0.3048)
			(end 0.508 -0.3048)
			(stroke
				(width 0.1)
				(type default)
			)
			(layer "F.Fab")
		)
		(fp_line
			(start -0.508 -0.3048)
			(end -0.508 0.3048)
			(stroke
				(width 0.1)
				(type default)
			)
			(layer "F.Fab")
		)
		(fp_line
			(start 0.508 -0.3048)
			(end -0.508 -0.3048)
			(stroke
				(width 0.1)
				(type default)
			)
			(layer "F.Fab")
		)
		(pad "1" smd rect
			(at -0.5334 0 270)
			(size 0.7112 0.6096)
			(layers "F.Cu" "F.Mask" "F.Paste")
			(net "FT_USB_DP")
		)
		(pad "2" smd rect
			(at 0.5334 0 270)
			(size 0.7112 0.6096)
			(layers "F.Cu" "F.Mask" "F.Paste")
			(net "R_FT_USB_DP")
		)
		(zone
			(layer "F.Cu")
			(hatch none 0.5)
			(connect_pads
				(clearance 0)
			)
			(min_thickness 0.25)
			(keepout
				(tracks not_allowed)
				(vias allowed)
				(pads allowed)
				(copperpour not_allowed)
				(footprints allowed)
			)
			(placement
				(enabled no)
				(sheetname "")
			)
			(fill
				(thermal_gap 0.5)
				(thermal_bridge_width 0.5)
				(island_removal_mode 0)
			)
			(polygon
				(pts
					(xy 27.7622 -94.3102) (xy 27.7622 -94.1578) (xy 28.3718 -94.1578) (xy 28.3718 -94.3102)
				)
			)
		)
		(zone
			(layer "F.Cu")
			(hatch none 0.5)
			(connect_pads
				(clearance 0)
			)
			(min_thickness 0.25)
			(keepout
				(tracks allowed)
				(vias not_allowed)
				(pads allowed)
				(copperpour not_allowed)
				(footprints allowed)
			)
			(placement
				(enabled no)
				(sheetname "")
			)
			(fill
				(thermal_gap 0.5)
				(thermal_bridge_width 0.5)
				(island_removal_mode 0)
			)
			(polygon
				(pts
					(xy 27.7622 -94.3102) (xy 27.7622 -94.1578) (xy 28.3718 -94.1578) (xy 28.3718 -94.3102)
				)
			)
		)
	)
	(footprint ""
		(layer "F.Cu")
		(at 21.209 -64.643 -90)
		(property "Reference" "R351"
			(at 1.27 -4.10337 90)
			(unlocked yes)
			(layer "F.SilkS")
			(effects
				(font
					(size 0.7874 0.5842)
					(thickness 0.1524)
				)
			)
		)
		(property "Value" "VAL*"
			(at 0.02032 2.13233 270)
			(unlocked yes)
			(layer "F.Fab")
			(hide yes)
			(effects
				(font
					(size 0.7874 0.5842)
					(thickness 0.1524)
				)
			)
		)
		(property "Tolerance" "TOL*"
			(at 0.044704 3.05435 270)
			(unlocked yes)
			(layer "Cmts.User")
			(hide yes)
			(effects
				(font
					(size 0.7874 0.5842)
					(thickness 0.1524)
				)
			)
		)
		(property "User Part Number" "PARTNUM*"
			(at 0.02032 4.024884 270)
			(unlocked yes)
			(layer "Cmts.User")
			(hide yes)
			(effects
				(font
					(size 0.7874 0.5842)
					(thickness 0.1524)
				)
			)
		)
		(property "Device Type" "RESISTOR-G155-100R0-J0,0OHM,-"
			(at 0.008382 1.210564 270)
			(unlocked yes)
			(layer "F.Fab")
			(hide yes)
			(effects
				(font
					(size 0.7874 0.5842)
					(thickness 0.1524)
				)
			)
		)
		(duplicate_pad_numbers_are_jumpers no)
		(fp_line
			(start -1.143 0.5588)
			(end 1.143 0.5588)
			(stroke
				(width 0.1)
				(type default)
			)
			(layer "F.SilkS")
		)
		(fp_line
			(start 1.143 0.5588)
			(end 1.143 -0.5588)
			(stroke
				(width 0.1)
				(type default)
			)
			(layer "F.SilkS")
		)
		(fp_line
			(start -1.143 -0.5588)
			(end -1.143 0.5588)
			(stroke
				(width 0.1)
				(type default)
			)
			(layer "F.SilkS")
		)
		(fp_line
			(start 1.143 -0.5588)
			(end -1.143 -0.5588)
			(stroke
				(width 0.1)
				(type default)
			)
			(layer "F.SilkS")
		)
		(fp_poly
			(pts
				(xy -1.143 0.5588) (xy 1.143 0.5588) (xy 1.143 -0.5588) (xy -1.143 -0.5588)
			)
			(stroke
				(width 0)
				(type default)
			)
			(fill no)
			(layer "F.CrtYd")
		)
		(fp_line
			(start -0.508 0.3048)
			(end 0.508 0.3048)
			(stroke
				(width 0.1)
				(type default)
			)
			(layer "F.Fab")
		)
		(fp_line
			(start 0.508 0.3048)
			(end 0.508 -0.3048)
			(stroke
				(width 0.1)
				(type default)
			)
			(layer "F.Fab")
		)
		(fp_line
			(start -0.508 -0.3048)
			(end -0.508 0.3048)
			(stroke
				(width 0.1)
				(type default)
			)
			(layer "F.Fab")
		)
		(fp_line
			(start 0.508 -0.3048)
			(end -0.508 -0.3048)
			(stroke
				(width 0.1)
				(type default)
			)
			(layer "F.Fab")
		)
		(pad "1" smd rect
			(at -0.5334 0 270)
			(size 0.7112 0.6096)
			(layers "F.Cu" "F.Mask" "F.Paste")
			(net "UNNAMED_8_ICP10100LGA10_I24_R_4")
		)
		(pad "2" smd rect
			(at 0.5334 0 270)
			(size 0.7112 0.6096)
			(layers "F.Cu" "F.Mask" "F.Paste")
			(net "SG")
		)
		(zone
			(layer "F.Cu")
			(hatch none 0.5)
			(connect_pads
				(clearance 0)
			)
			(min_thickness 0.25)
			(keepout
				(tracks allowed)
				(vias not_allowed)
				(pads allowed)
				(copperpour not_allowed)
				(footprints allowed)
			)
			(placement
				(enabled no)
				(sheetname "")
			)
			(fill
				(thermal_gap 0.5)
				(thermal_bridge_width 0.5)
				(island_removal_mode 0)
			)
			(polygon
				(pts
					(xy 20.9042 -64.7192) (xy 20.9042 -64.5668) (xy 21.5138 -64.5668) (xy 21.5138 -64.7192)
				)
			)
		)
		(zone
			(layer "F.Cu")
			(hatch none 0.5)
			(connect_pads
				(clearance 0)
			)
			(min_thickness 0.25)
			(keepout
				(tracks not_allowed)
				(vias allowed)
				(pads allowed)
				(copperpour not_allowed)
				(footprints allowed)
			)
			(placement
				(enabled no)
				(sheetname "")
			)
			(fill
				(thermal_gap 0.5)
				(thermal_bridge_width 0.5)
				(island_removal_mode 0)
			)
			(polygon
				(pts
					(xy 20.9042 -64.7192) (xy 20.9042 -64.5668) (xy 21.5138 -64.5668) (xy 21.5138 -64.7192)
				)
			)
		)
	)
	(footprint ""
		(layer "F.Cu")
		(at 30.34538 -15.58544)
		(property "Reference" "C225"
			(at -0.889 -5.29463 0)
			(unlocked yes)
			(layer "F.SilkS")
			(effects
				(font
					(size 0.7874 0.5842)
					(thickness 0.1524)
				)
			)
		)
		(property "Value" "VAL*"
			(at 0.0762 2.067306 0)
			(unlocked yes)
			(layer "F.Fab")
			(hide yes)
			(effects
				(font
					(size 0.7874 0.5842)
					(thickness 0.1524)
				)
			)
		)
		(property "Tolerance" "TOL*"
			(at 0.0762 3.032506 0)
			(unlocked yes)
			(layer "Cmts.User")
			(hide yes)
			(effects
				(font
					(size 0.7874 0.5842)
					(thickness 0.1524)
				)
			)
		)
		(property "User Part Number" "PARTNUM*"
			(at 0.1016 4.023106 0)
			(unlocked yes)
			(layer "Cmts.User")
			(hide yes)
			(effects
				(font
					(size 0.7874 0.5842)
					(thickness 0.1524)
				)
			)
		)
		(property "Device Type" "CAPACITOR-G105-0B104-EK,0.1UF,A"
			(at 0.0508 1.127506 0)
			(unlocked yes)
			(layer "F.Fab")
			(hide yes)
			(effects
				(font
					(size 0.7874 0.5842)
					(thickness 0.1524)
				)
			)
		)
		(duplicate_pad_numbers_are_jumpers no)
		(fp_line
			(start -1.143 -0.5588)
			(end -1.143 0.5588)
			(stroke
				(width 0.1)
				(type default)
			)
			(layer "F.SilkS")
		)
		(fp_line
			(start -1.143 0.5588)
			(end 1.143 0.5588)
			(stroke
				(width 0.1)
				(type default)
			)
			(layer "F.SilkS")
		)
		(fp_line
			(start 1.143 -0.5588)
			(end -1.143 -0.5588)
			(stroke
				(width 0.1)
				(type default)
			)
			(layer "F.SilkS")
		)
		(fp_line
			(start 1.143 0.5588)
			(end 1.143 -0.5588)
			(stroke
				(width 0.1)
				(type default)
			)
			(layer "F.SilkS")
		)
		(fp_rect
			(start -1.143 0.5588)
			(end 1.143 -0.5588)
			(stroke
				(width 0)
				(type default)
			)
			(fill no)
			(layer "F.CrtYd")
		)
		(fp_line
			(start -0.508 -0.3048)
			(end -0.508 0.3048)
			(stroke
				(width 0.1)
				(type default)
			)
			(layer "F.Fab")
		)
		(fp_line
			(start -0.508 0.3048)
			(end 0.508 0.3048)
			(stroke
				(width 0.1)
				(type default)
			)
			(layer "F.Fab")
		)
		(fp_line
			(start 0.508 -0.3048)
			(end -0.508 -0.3048)
			(stroke
				(width 0.1)
				(type default)
			)
			(layer "F.Fab")
		)
		(fp_line
			(start 0.508 0.3048)
			(end 0.508 -0.3048)
			(stroke
				(width 0.1)
				(type default)
			)
			(layer "F.Fab")
		)
		(pad "1" smd rect
			(at -0.5334 0)
			(size 0.7112 0.6096)
			(layers "F.Cu" "F.Mask" "F.Paste")
			(net "XP3R3V_FPGA")
		)
		(pad "2" smd rect
			(at 0.5334 0)
			(size 0.7112 0.6096)
			(layers "F.Cu" "F.Mask" "F.Paste")
			(net "SG")
		)
		(zone
			(layer "F.Cu")
			(hatch none 0.5)
			(connect_pads
				(clearance 0)
			)
			(min_thickness 0.25)
			(keepout
				(tracks allowed)
				(vias not_allowed)
				(pads allowed)
				(copperpour not_allowed)
				(footprints allowed)
			)
			(placement
				(enabled no)
				(sheetname "")
			)
			(fill
				(thermal_gap 0.5)
				(thermal_bridge_width 0.5)
				(island_removal_mode 0)
			)
			(polygon
				(pts
					(xy 30.26918 -15.28064) (xy 30.42158 -15.28064) (xy 30.42158 -15.89024) (xy 30.26918 -15.89024)
				)
			)
		)
	)
	(footprint ""
		(layer "F.Cu")
		(at 44.831 -128.016)
		(property "Reference" "SP42"
			(at 0 0 0)
			(layer "F.SilkS")
			(hide yes)
			(effects
				(font
					(size 1.27 1.27)
				)
			)
		)
		(property "Value" ""
			(at 0 0 0)
			(layer "F.Fab")
			(effects
				(font
					(size 1.27 1.27)
				)
			)
		)
		(duplicate_pad_numbers_are_jumpers no)
	)
	(footprint ""
		(layer "F.Cu")
		(at 38.608 -123.19)
		(property "Reference" "SP76"
			(at 0 0 0)
			(layer "F.SilkS")
			(hide yes)
			(effects
				(font
					(size 1.27 1.27)
				)
			)
		)
		(property "Value" ""
			(at 0 0 0)
			(layer "F.Fab")
			(effects
				(font
					(size 1.27 1.27)
				)
			)
		)
		(duplicate_pad_numbers_are_jumpers no)
	)
)
